# T6G (Grand Teton) — schematic netlist excerpt (pin names and nets, part order shuffled) for the footprints in the layout excerpt that follows; sources: Cadence DE-HDL packaged netlist, KiCad conversion of 04192023_DAF0TMB3IC0_F0TG_MB_C_brd_V02_OCP.brd

C6719  Q_CAP_DIFFBUS  DIFF BUS_0.22UF 6.3V 20% X6S  pkg C0201  page 341 : \1\ = P5E_CPU1_P2_TX_BUF_C_DP<13> ; \2\ = P5E_CPU1_P2_TX_BUF_DP<13>
R6172  Q_RES  1K 1% CHIP  pkg 0402LF  page 112 : A = FM_P2E_BUF2_EQA1 ; B = GND
R3603  Q_RES  10 1% CHIP  pkg 0402LF  page 236 : A = P3V3_OCP_SFF ; B = VSENSE_P3V3_INA230_1_INN

(kicad_pcb
	(version 20260206)
	(generator "pcbnew")
	(generator_version "10.0")
	(general
		(thickness 1.6)
		(legacy_teardrops no)
	)
	(paper "A4")
	(title_block
		(title "04192023_DAF0TMB3IC0_F0TG_MB_C_brd_V02_OCP.brd")
		(comment 1 "Grand Teton / footprints 521-523 of 8354")
	)
	(layers
		(0 "F.Cu" signal "TOP")
		(4 "In1.Cu" signal "GND")
		(6 "In2.Cu" signal "IN1")
		(8 "In3.Cu" signal "GND1")
		(10 "In4.Cu" signal "IN2")
		(12 "In5.Cu" signal "GND2")
		(14 "In6.Cu" signal "IN3")
		(16 "In7.Cu" signal "GND3")
		(18 "In8.Cu" signal "VCC")
		(20 "In9.Cu" signal "VCC1")
		(22 "In10.Cu" signal "GND4")
		(24 "In11.Cu" signal "IN4")
		(26 "In12.Cu" signal "GND5")
		(28 "In13.Cu" signal "IN5")
		(30 "In14.Cu" signal "GND6")
		(32 "In15.Cu" signal "IN6")
		(34 "In16.Cu" signal "GND7")
		(2 "B.Cu" signal "BOTTOM")
		(9 "F.Adhes" user "F.Adhesive")
		(11 "B.Adhes" user "B.Adhesive")
		(13 "F.Paste" user "Package Geometry/Pastemask Top")
		(15 "B.Paste" user "Package Geometry/Pastemask Bottom")
		(5 "F.SilkS" user "Ref Des/Silkscreen Top")
		(7 "B.SilkS" user "Ref Des/Silkscreen Bottom")
		(1 "F.Mask" user "Board Geometry/Soldermask Top")
		(3 "B.Mask" user "Board Geometry/Soldermask Bottom")
		(17 "Dwgs.User" user "User.Drawings")
		(19 "Cmts.User" user "User.Comments")
		(21 "Eco1.User" user "User.Eco1")
		(23 "Eco2.User" user "User.Eco2")
		(25 "Edge.Cuts" user "Board Geometry/Outline")
		(27 "Margin" user)
		(31 "F.CrtYd" user "Package Geometry/Place Bound Top")
		(29 "B.CrtYd" user "Package Geometry/Place Bound Bottom")
		(35 "F.Fab" user "Ref Des/Assembly Top")
		(33 "B.Fab" user "Ref Des/Assembly Bottom")
	)
	(footprint ""
		(layer "F.Cu")
		(at 432.636676 -94.938342)
		(property "Reference" "R3603"
			(at 0 0 0)
			(layer "F.SilkS")
			(hide yes)
			(effects
				(font
					(size 1.27 1.27)
				)
			)
		)
		(property "Value" ""
			(at 0 0 0)
			(layer "F.Fab")
			(effects
				(font
					(size 1.27 1.27)
				)
			)
		)
		(duplicate_pad_numbers_are_jumpers no)
		(fp_line
			(start -0.7874 -0.4064)
			(end 0.7874 -0.4064)
			(stroke
				(width 0.1524)
				(type default)
			)
			(layer "F.SilkS")
		)
		(fp_line
			(start -0.7874 0.4064)
			(end -0.7874 -0.4064)
			(stroke
				(width 0.1524)
				(type default)
			)
			(layer "F.SilkS")
		)
		(fp_line
			(start 0.7874 -0.4064)
			(end 0.7874 0.4064)
			(stroke
				(width 0.1524)
				(type default)
			)
			(layer "F.SilkS")
		)
		(fp_line
			(start 0.7874 0.4064)
			(end -0.7874 0.4064)
			(stroke
				(width 0.1524)
				(type default)
			)
			(layer "F.SilkS")
		)
		(fp_line
			(start -0.67945 -0.305054)
			(end -0.12065 -0.305054)
			(stroke
				(width 0.1)
				(type default)
			)
			(layer "F.Fab")
		)
		(fp_line
			(start -0.67945 0.3048)
			(end -0.67945 -0.305054)
			(stroke
				(width 0.1)
				(type default)
			)
			(layer "F.Fab")
		)
		(fp_line
			(start -0.12065 -0.305054)
			(end -0.12065 -0.2794)
			(stroke
				(width 0.1)
				(type default)
			)
			(layer "F.Fab")
		)
		(fp_line
			(start -0.12065 -0.2794)
			(end 0.12065 -0.2794)
			(stroke
				(width 0.1)
				(type default)
			)
			(layer "F.Fab")
		)
		(fp_line
			(start -0.12065 0.2794)
			(end -0.12065 0.3048)
			(stroke
				(width 0.1)
				(type default)
			)
			(layer "F.Fab")
		)
		(fp_line
			(start -0.12065 0.3048)
			(end -0.67945 0.3048)
			(stroke
				(width 0.1)
				(type default)
			)
			(layer "F.Fab")
		)
		(fp_line
			(start 0.120396 0.2794)
			(end -0.12065 0.2794)
			(stroke
				(width 0.1)
				(type default)
			)
			(layer "F.Fab")
		)
		(fp_line
			(start 0.120396 0.3048)
			(end 0.120396 0.2794)
			(stroke
				(width 0.1)
				(type default)
			)
			(layer "F.Fab")
		)
		(fp_line
			(start 0.12065 -0.3048)
			(end 0.67945 -0.3048)
			(stroke
				(width 0.1)
				(type default)
			)
			(layer "F.Fab")
		)
		(fp_line
			(start 0.12065 -0.2794)
			(end 0.12065 -0.3048)
			(stroke
				(width 0.1)
				(type default)
			)
			(layer "F.Fab")
		)
		(fp_line
			(start 0.67945 -0.3048)
			(end 0.67945 0.3048)
			(stroke
				(width 0.1)
				(type default)
			)
			(layer "F.Fab")
		)
		(fp_line
			(start 0.67945 0.3048)
			(end 0.120396 0.3048)
			(stroke
				(width 0.1)
				(type default)
			)
			(layer "F.Fab")
		)
		(pad "1" smd circle
			(at -0.40005 0)
			(size 0 0)
			(layers "F.Cu" "F.Mask" "F.Paste")
			(net "P3V3_OCP_SFF")
		)
		(pad "2" smd circle
			(at 0.40005 0)
			(size 0 0)
			(layers "F.Cu" "F.Mask" "F.Paste")
			(net "VSENSE_P3V3_INA230_1_INN")
		)
	)
	(footprint ""
		(layer "F.Cu")
		(at 155.605226 -408.517344 -90)
		(property "Reference" "C6719"
			(at 0 0 270)
			(layer "F.SilkS")
			(hide yes)
			(effects
				(font
					(size 1.27 1.27)
				)
			)
		)
		(property "Value" ""
			(at 0 0 270)
			(layer "F.Fab")
			(effects
				(font
					(size 1.27 1.27)
				)
			)
		)
		(duplicate_pad_numbers_are_jumpers no)
		(fp_line
			(start -0.299974 0.150114)
			(end -0.299974 -0.150114)
			(stroke
				(width 0.1)
				(type default)
			)
			(layer "F.Fab")
		)
		(fp_line
			(start 0.299974 0.150114)
			(end -0.299974 0.150114)
			(stroke
				(width 0.1)
				(type default)
			)
			(layer "F.Fab")
		)
		(fp_line
			(start -0.299974 -0.150114)
			(end 0.299974 -0.150114)
			(stroke
				(width 0.1)
				(type default)
			)
			(layer "F.Fab")
		)
		(fp_line
			(start 0.299974 -0.150114)
			(end 0.299974 0.150114)
			(stroke
				(width 0.1)
				(type default)
			)
			(layer "F.Fab")
		)
		(pad "1" smd rect
			(at -0.2667 0 270)
			(size 0.3048 0.381)
			(layers "F.Cu" "F.Mask" "F.Paste")
			(net "P5E_CPU1_P2_TX_BUF_C_DP<13>")
		)
		(pad "2" smd rect
			(at 0.2667 0 270)
			(size 0.3048 0.381)
			(layers "F.Cu" "F.Mask" "F.Paste")
			(net "P5E_CPU1_P2_TX_BUF_DP<13>")
		)
	)
	(footprint ""
		(layer "F.Cu")
		(at 11.665458 -423.821098 180)
		(property "Reference" "R6172"
			(at 0 0 180)
			(layer "F.SilkS")
			(hide yes)
			(effects
				(font
					(size 1.27 1.27)
				)
			)
		)
		(property "Value" ""
			(at 0 0 180)
			(layer "F.Fab")
			(effects
				(font
					(size 1.27 1.27)
				)
			)
		)
		(duplicate_pad_numbers_are_jumpers no)
		(fp_line
			(start 0.7874 0.4064)
			(end -0.7874 0.4064)
			(stroke
				(width 0.1524)
				(type default)
			)
			(layer "F.SilkS")
		)
		(fp_line
			(start 0.7874 -0.4064)
			(end 0.7874 0.4064)
			(stroke
				(width 0.1524)
				(type default)
			)
			(layer "F.SilkS")
		)
		(fp_line
			(start -0.7874 0.4064)
			(end -0.7874 -0.4064)
			(stroke
				(width 0.1524)
				(type default)
			)
			(layer "F.SilkS")
		)
		(fp_line
			(start -0.7874 -0.4064)
			(end 0.7874 -0.4064)
			(stroke
				(width 0.1524)
				(type default)
			)
			(layer "F.SilkS")
		)
		(fp_line
			(start 0.67945 0.3048)
			(end 0.120396 0.3048)
			(stroke
				(width 0.1)
				(type default)
			)
			(layer "F.Fab")
		)
		(fp_line
			(start 0.67945 -0.3048)
			(end 0.67945 0.3048)
			(stroke
				(width 0.1)
				(type default)
			)
			(layer "F.Fab")
		)
		(fp_line
			(start 0.12065 -0.2794)
			(end 0.12065 -0.3048)
			(stroke
				(width 0.1)
				(type default)
			)
			(layer "F.Fab")
		)
		(fp_line
			(start 0.12065 -0.3048)
			(end 0.67945 -0.3048)
			(stroke
				(width 0.1)
				(type default)
			)
			(layer "F.Fab")
		)
		(fp_line
			(start 0.120396 0.3048)
			(end 0.120396 0.2794)
			(stroke
				(width 0.1)
				(type default)
			)
			(layer "F.Fab")
		)
		(fp_line
			(start 0.120396 0.2794)
			(end -0.12065 0.2794)
			(stroke
				(width 0.1)
				(type default)
			)
			(layer "F.Fab")
		)
		(fp_line
			(start -0.12065 0.3048)
			(end -0.67945 0.3048)
			(stroke
				(width 0.1)
				(type default)
			)
			(layer "F.Fab")
		)
		(fp_line
			(start -0.12065 0.2794)
			(end -0.12065 0.3048)
			(stroke
				(width 0.1)
				(type default)
			)
			(layer "F.Fab")
		)
		(fp_line
			(start -0.12065 -0.2794)
			(end 0.12065 -0.2794)
			(stroke
				(width 0.1)
				(type default)
			)
			(layer "F.Fab")
		)
		(fp_line
			(start -0.12065 -0.305054)
			(end -0.12065 -0.2794)
			(stroke
				(width 0.1)
				(type default)
			)
			(layer "F.Fab")
		)
		(fp_line
			(start -0.67945 0.3048)
			(end -0.67945 -0.305054)
			(stroke
				(width 0.1)
				(type default)
			)
			(layer "F.Fab")
		)
		(fp_line
			(start -0.67945 -0.305054)
			(end -0.12065 -0.305054)
			(stroke
				(width 0.1)
				(type default)
			)
			(layer "F.Fab")
		)
		(pad "1" smd circle
			(at -0.40005 0 180)
			(size 0 0)
			(layers "F.Cu" "F.Mask" "F.Paste")
			(net "FM_P2E_BUF2_EQA1")
		)
		(pad "2" smd circle
			(at 0.40005 0 180)
			(size 0 0)
			(layers "F.Cu" "F.Mask" "F.Paste")
			(net "GND")
		)
	)
)
